(kicad_pcb
	(version 20260206)
	(generator "pcbnew")
	(generator_version "10.0")
	(general
		(thickness 1.6)
		(legacy_teardrops no)
	)
	(paper "A4")
	(title_block
		(title "04192023_DAF0TMB3IC0_F0TG_MB_C_brd_V02_OCP.brd")
		(comment 1 "Grand Teton / footprints 4945-4951 of 8354")
	)
	(layers
		(0 "F.Cu" signal "TOP")
		(4 "In1.Cu" signal "GND")
		(6 "In2.Cu" signal "IN1")
		(8 "In3.Cu" signal "GND1")
		(10 "In4.Cu" signal "IN2")
		(12 "In5.Cu" signal "GND2")
		(14 "In6.Cu" signal "IN3")
		(16 "In7.Cu" signal "GND3")
		(18 "In8.Cu" signal "VCC")
		(20 "In9.Cu" signal "VCC1")
		(22 "In10.Cu" signal "GND4")
		(24 "In11.Cu" signal "IN4")
		(26 "In12.Cu" signal "GND5")
		(28 "In13.Cu" signal "IN5")
		(30 "In14.Cu" signal "GND6")
		(32 "In15.Cu" signal "IN6")
		(34 "In16.Cu" signal "GND7")
		(2 "B.Cu" signal "BOTTOM")
		(9 "F.Adhes" user "F.Adhesive")
		(11 "B.Adhes" user "B.Adhesive")
		(13 "F.Paste" user "Package Geometry/Pastemask Top")
		(15 "B.Paste" user "Package Geometry/Pastemask Bottom")
		(5 "F.SilkS" user "Ref Des/Silkscreen Top")
		(7 "B.SilkS" user "Ref Des/Silkscreen Bottom")
		(1 "F.Mask" user "Board Geometry/Soldermask Top")
		(3 "B.Mask" user "Board Geometry/Soldermask Bottom")
		(17 "Dwgs.User" user "User.Drawings")
		(19 "Cmts.User" user "User.Comments")
		(21 "Eco1.User" user "User.Eco1")
		(23 "Eco2.User" user "User.Eco2")
		(25 "Edge.Cuts" user "Board Geometry/Outline")
		(27 "Margin" user)
		(31 "F.CrtYd" user "Package Geometry/Place Bound Top")
		(29 "B.CrtYd" user "Package Geometry/Place Bound Bottom")
		(35 "F.Fab" user "Ref Des/Assembly Top")
		(33 "B.Fab" user "Ref Des/Assembly Bottom")
	)
	(footprint ""
		(layer "B.Cu")
		(at 356.057454 -253.43231)
		(property "Reference" "C2549"
			(at 0 0 0)
			(layer "B.SilkS")
			(hide yes)
			(effects
				(font
					(size 1.27 1.27)
				)
				(justify mirror)
			)
		)
		(property "Value" ""
			(at 0 0 0)
			(layer "B.Fab")
			(effects
				(font
					(size 1.27 1.27)
				)
				(justify mirror)
			)
		)
		(duplicate_pad_numbers_are_jumpers no)
		(fp_line
			(start -0.7874 -0.4064)
			(end -0.7874 0.4064)
			(stroke
				(width 0.1524)
				(type default)
			)
			(layer "B.SilkS")
		)
		(fp_line
			(start -0.7874 0.4064)
			(end 0.7874 0.4064)
			(stroke
				(width 0.1524)
				(type default)
			)
			(layer "B.SilkS")
		)
		(fp_line
			(start 0.7874 -0.4064)
			(end -0.7874 -0.4064)
			(stroke
				(width 0.1524)
				(type default)
			)
			(layer "B.SilkS")
		)
		(fp_line
			(start 0.7874 0.4064)
			(end 0.7874 -0.4064)
			(stroke
				(width 0.1524)
				(type default)
			)
			(layer "B.SilkS")
		)
		(fp_line
			(start -0.67945 -0.3048)
			(end -0.67945 0.3048)
			(stroke
				(width 0.1)
				(type default)
			)
			(layer "B.Fab")
		)
		(fp_line
			(start -0.67945 0.3048)
			(end -0.120396 0.3048)
			(stroke
				(width 0.1)
				(type default)
			)
			(layer "B.Fab")
		)
		(fp_line
			(start -0.12065 -0.3048)
			(end -0.67945 -0.3048)
			(stroke
				(width 0.1)
				(type default)
			)
			(layer "B.Fab")
		)
		(fp_line
			(start -0.12065 -0.2794)
			(end -0.12065 -0.3048)
			(stroke
				(width 0.1)
				(type default)
			)
			(layer "B.Fab")
		)
		(fp_line
			(start -0.120396 0.2794)
			(end 0.12065 0.2794)
			(stroke
				(width 0.1)
				(type default)
			)
			(layer "B.Fab")
		)
		(fp_line
			(start -0.120396 0.3048)
			(end -0.120396 0.2794)
			(stroke
				(width 0.1)
				(type default)
			)
			(layer "B.Fab")
		)
		(fp_line
			(start 0.12065 -0.305054)
			(end 0.12065 -0.2794)
			(stroke
				(width 0.1)
				(type default)
			)
			(layer "B.Fab")
		)
		(fp_line
			(start 0.12065 -0.2794)
			(end -0.12065 -0.2794)
			(stroke
				(width 0.1)
				(type default)
			)
			(layer "B.Fab")
		)
		(fp_line
			(start 0.12065 0.2794)
			(end 0.12065 0.3048)
			(stroke
				(width 0.1)
				(type default)
			)
			(layer "B.Fab")
		)
		(fp_line
			(start 0.12065 0.3048)
			(end 0.67945 0.3048)
			(stroke
				(width 0.1)
				(type default)
			)
			(layer "B.Fab")
		)
		(fp_line
			(start 0.67945 -0.305054)
			(end 0.12065 -0.305054)
			(stroke
				(width 0.1)
				(type default)
			)
			(layer "B.Fab")
		)
		(fp_line
			(start 0.67945 0.3048)
			(end 0.67945 -0.305054)
			(stroke
				(width 0.1)
				(type default)
			)
			(layer "B.Fab")
		)
		(pad "1" smd circle
			(at 0.40005 0 180)
			(size 0 0)
			(layers "B.Cu" "B.Mask" "B.Paste")
			(net "PVDDCR_SOC_P0")
		)
		(pad "2" smd circle
			(at -0.40005 0 180)
			(size 0 0)
			(layers "B.Cu" "B.Mask" "B.Paste")
			(net "GND")
		)
	)
	(footprint ""
		(layer "B.Cu")
		(at 375.456958 -208.530952 90)
		(property "Reference" "C209"
			(at 0 0 90)
			(layer "B.SilkS")
			(hide yes)
			(effects
				(font
					(size 1.27 1.27)
				)
				(justify mirror)
			)
		)
		(property "Value" ""
			(at 0 0 90)
			(layer "B.Fab")
			(effects
				(font
					(size 1.27 1.27)
				)
				(justify mirror)
			)
		)
		(duplicate_pad_numbers_are_jumpers no)
		(fp_line
			(start 0.7874 -0.4064)
			(end -0.7874 -0.4064)
			(stroke
				(width 0.1524)
				(type default)
			)
			(layer "B.SilkS")
		)
		(fp_line
			(start -0.7874 -0.4064)
			(end -0.7874 0.4064)
			(stroke
				(width 0.1524)
				(type default)
			)
			(layer "B.SilkS")
		)
		(fp_line
			(start 0.7874 0.4064)
			(end 0.7874 -0.4064)
			(stroke
				(width 0.1524)
				(type default)
			)
			(layer "B.SilkS")
		)
		(fp_line
			(start -0.7874 0.4064)
			(end 0.7874 0.4064)
			(stroke
				(width 0.1524)
				(type default)
			)
			(layer "B.SilkS")
		)
		(fp_line
			(start 0.67945 -0.305054)
			(end 0.12065 -0.305054)
			(stroke
				(width 0.1)
				(type default)
			)
			(layer "B.Fab")
		)
		(fp_line
			(start 0.12065 -0.305054)
			(end 0.12065 -0.2794)
			(stroke
				(width 0.1)
				(type default)
			)
			(layer "B.Fab")
		)
		(fp_line
			(start -0.12065 -0.3048)
			(end -0.67945 -0.3048)
			(stroke
				(width 0.1)
				(type default)
			)
			(layer "B.Fab")
		)
		(fp_line
			(start -0.67945 -0.3048)
			(end -0.67945 0.3048)
			(stroke
				(width 0.1)
				(type default)
			)
			(layer "B.Fab")
		)
		(fp_line
			(start 0.12065 -0.2794)
			(end -0.12065 -0.2794)
			(stroke
				(width 0.1)
				(type default)
			)
			(layer "B.Fab")
		)
		(fp_line
			(start -0.12065 -0.2794)
			(end -0.12065 -0.3048)
			(stroke
				(width 0.1)
				(type default)
			)
			(layer "B.Fab")
		)
		(fp_line
			(start 0.12065 0.2794)
			(end 0.12065 0.3048)
			(stroke
				(width 0.1)
				(type default)
			)
			(layer "B.Fab")
		)
		(fp_line
			(start -0.120396 0.2794)
			(end 0.12065 0.2794)
			(stroke
				(width 0.1)
				(type default)
			)
			(layer "B.Fab")
		)
		(fp_line
			(start 0.67945 0.3048)
			(end 0.67945 -0.305054)
			(stroke
				(width 0.1)
				(type default)
			)
			(layer "B.Fab")
		)
		(fp_line
			(start 0.12065 0.3048)
			(end 0.67945 0.3048)
			(stroke
				(width 0.1)
				(type default)
			)
			(layer "B.Fab")
		)
		(fp_line
			(start -0.120396 0.3048)
			(end -0.120396 0.2794)
			(stroke
				(width 0.1)
				(type default)
			)
			(layer "B.Fab")
		)
		(fp_line
			(start -0.67945 0.3048)
			(end -0.120396 0.3048)
			(stroke
				(width 0.1)
				(type default)
			)
			(layer "B.Fab")
		)
		(pad "1" smd circle
			(at 0.40005 0 270)
			(size 0 0)
			(layers "B.Cu" "B.Mask" "B.Paste")
			(net "JTAG_CPU0_TRST_N")
		)
		(pad "2" smd circle
			(at -0.40005 0 270)
			(size 0 0)
			(layers "B.Cu" "B.Mask" "B.Paste")
			(net "GND")
		)
	)
	(footprint ""
		(layer "B.Cu")
		(at 88.319102 -390.560052 90)
		(property "Reference" "C195"
			(at 0 0 90)
			(layer "B.SilkS")
			(hide yes)
			(effects
				(font
					(size 1.27 1.27)
				)
				(justify mirror)
			)
		)
		(property "Value" ""
			(at 0 0 90)
			(layer "B.Fab")
			(effects
				(font
					(size 1.27 1.27)
				)
				(justify mirror)
			)
		)
		(duplicate_pad_numbers_are_jumpers no)
		(fp_line
			(start 0.7874 -0.4064)
			(end -0.7874 -0.4064)
			(stroke
				(width 0.1524)
				(type default)
			)
			(layer "B.SilkS")
		)
		(fp_line
			(start -0.7874 -0.4064)
			(end -0.7874 0.4064)
			(stroke
				(width 0.1524)
				(type default)
			)
			(layer "B.SilkS")
		)
		(fp_line
			(start 0.7874 0.4064)
			(end 0.7874 -0.4064)
			(stroke
				(width 0.1524)
				(type default)
			)
			(layer "B.SilkS")
		)
		(fp_line
			(start -0.7874 0.4064)
			(end 0.7874 0.4064)
			(stroke
				(width 0.1524)
				(type default)
			)
			(layer "B.SilkS")
		)
		(fp_line
			(start 0.67945 -0.305054)
			(end 0.12065 -0.305054)
			(stroke
				(width 0.1)
				(type default)
			)
			(layer "B.Fab")
		)
		(fp_line
			(start 0.12065 -0.305054)
			(end 0.12065 -0.2794)
			(stroke
				(width 0.1)
				(type default)
			)
			(layer "B.Fab")
		)
		(fp_line
			(start -0.12065 -0.3048)
			(end -0.67945 -0.3048)
			(stroke
				(width 0.1)
				(type default)
			)
			(layer "B.Fab")
		)
		(fp_line
			(start -0.67945 -0.3048)
			(end -0.67945 0.3048)
			(stroke
				(width 0.1)
				(type default)
			)
			(layer "B.Fab")
		)
		(fp_line
			(start 0.12065 -0.2794)
			(end -0.12065 -0.2794)
			(stroke
				(width 0.1)
				(type default)
			)
			(layer "B.Fab")
		)
		(fp_line
			(start -0.12065 -0.2794)
			(end -0.12065 -0.3048)
			(stroke
				(width 0.1)
				(type default)
			)
			(layer "B.Fab")
		)
		(fp_line
			(start 0.12065 0.2794)
			(end 0.12065 0.3048)
			(stroke
				(width 0.1)
				(type default)
			)
			(layer "B.Fab")
		)
		(fp_line
			(start -0.120396 0.2794)
			(end 0.12065 0.2794)
			(stroke
				(width 0.1)
				(type default)
			)
			(layer "B.Fab")
		)
		(fp_line
			(start 0.67945 0.3048)
			(end 0.67945 -0.305054)
			(stroke
				(width 0.1)
				(type default)
			)
			(layer "B.Fab")
		)
		(fp_line
			(start 0.12065 0.3048)
			(end 0.67945 0.3048)
			(stroke
				(width 0.1)
				(type default)
			)
			(layer "B.Fab")
		)
		(fp_line
			(start -0.120396 0.3048)
			(end -0.120396 0.2794)
			(stroke
				(width 0.1)
				(type default)
			)
			(layer "B.Fab")
		)
		(fp_line
			(start -0.67945 0.3048)
			(end -0.120396 0.3048)
			(stroke
				(width 0.1)
				(type default)
			)
			(layer "B.Fab")
		)
		(pad "1" smd circle
			(at 0.40005 0 270)
			(size 0 0)
			(layers "B.Cu" "B.Mask" "B.Paste")
			(net "P1V8_CPU1_RT1_1A")
		)
		(pad "2" smd circle
			(at -0.40005 0 270)
			(size 0 0)
			(layers "B.Cu" "B.Mask" "B.Paste")
			(net "GND")
		)
	)
	(footprint ""
		(layer "B.Cu")
		(at 25.313386 -190.948564 180)
		(property "Reference" "R307"
			(at 0 0 0)
			(layer "B.SilkS")
			(hide yes)
			(effects
				(font
					(size 1.27 1.27)
				)
				(justify mirror)
			)
		)
		(property "Value" ""
			(at 0 0 0)
			(layer "B.Fab")
			(effects
				(font
					(size 1.27 1.27)
				)
				(justify mirror)
			)
		)
		(duplicate_pad_numbers_are_jumpers no)
		(fp_line
			(start 0.7874 0.4064)
			(end 0.7874 -0.4064)
			(stroke
				(width 0.1524)
				(type default)
			)
			(layer "B.SilkS")
		)
		(fp_line
			(start 0.7874 -0.4064)
			(end -0.7874 -0.4064)
			(stroke
				(width 0.1524)
				(type default)
			)
			(layer "B.SilkS")
		)
		(fp_line
			(start -0.7874 0.4064)
			(end 0.7874 0.4064)
			(stroke
				(width 0.1524)
				(type default)
			)
			(layer "B.SilkS")
		)
		(fp_line
			(start -0.7874 -0.4064)
			(end -0.7874 0.4064)
			(stroke
				(width 0.1524)
				(type default)
			)
			(layer "B.SilkS")
		)
		(fp_line
			(start 0.67945 0.3048)
			(end 0.67945 -0.305054)
			(stroke
				(width 0.1)
				(type default)
			)
			(layer "B.Fab")
		)
		(fp_line
			(start 0.67945 -0.305054)
			(end 0.12065 -0.305054)
			(stroke
				(width 0.1)
				(type default)
			)
			(layer "B.Fab")
		)
		(fp_line
			(start 0.12065 0.3048)
			(end 0.67945 0.3048)
			(stroke
				(width 0.1)
				(type default)
			)
			(layer "B.Fab")
		)
		(fp_line
			(start 0.12065 0.2794)
			(end 0.12065 0.3048)
			(stroke
				(width 0.1)
				(type default)
			)
			(layer "B.Fab")
		)
		(fp_line
			(start 0.12065 -0.2794)
			(end -0.12065 -0.2794)
			(stroke
				(width 0.1)
				(type default)
			)
			(layer "B.Fab")
		)
		(fp_line
			(start 0.12065 -0.305054)
			(end 0.12065 -0.2794)
			(stroke
				(width 0.1)
				(type default)
			)
			(layer "B.Fab")
		)
		(fp_line
			(start -0.120396 0.3048)
			(end -0.120396 0.2794)
			(stroke
				(width 0.1)
				(type default)
			)
			(layer "B.Fab")
		)
		(fp_line
			(start -0.120396 0.2794)
			(end 0.12065 0.2794)
			(stroke
				(width 0.1)
				(type default)
			)
			(layer "B.Fab")
		)
		(fp_line
			(start -0.12065 -0.2794)
			(end -0.12065 -0.3048)
			(stroke
				(width 0.1)
				(type default)
			)
			(layer "B.Fab")
		)
		(fp_line
			(start -0.12065 -0.3048)
			(end -0.67945 -0.3048)
			(stroke
				(width 0.1)
				(type default)
			)
			(layer "B.Fab")
		)
		(fp_line
			(start -0.67945 0.3048)
			(end -0.120396 0.3048)
			(stroke
				(width 0.1)
				(type default)
			)
			(layer "B.Fab")
		)
		(fp_line
			(start -0.67945 -0.3048)
			(end -0.67945 0.3048)
			(stroke
				(width 0.1)
				(type default)
			)
			(layer "B.Fab")
		)
		(pad "1" smd circle
			(at 0.40005 0)
			(size 0 0)
			(layers "B.Cu" "B.Mask" "B.Paste")
			(net "PWRGD_CHE_CPU1_DIMM")
		)
		(pad "2" smd circle
			(at -0.40005 0)
			(size 0 0)
			(layers "B.Cu" "B.Mask" "B.Paste")
			(net "PWRGD_CHAF_CPU1")
		)
	)
	(footprint ""
		(layer "B.Cu")
		(at 248.539 -332.105)
		(property "Reference" "C365"
			(at 0 0 0)
			(layer "B.SilkS")
			(hide yes)
			(effects
				(font
					(size 1.27 1.27)
				)
				(justify mirror)
			)
		)
		(property "Value" ""
			(at 0 0 0)
			(layer "B.Fab")
			(effects
				(font
					(size 1.27 1.27)
				)
				(justify mirror)
			)
		)
		(duplicate_pad_numbers_are_jumpers no)
		(fp_line
			(start -0.299974 -0.150114)
			(end -0.299974 0.150114)
			(stroke
				(width 0.1)
				(type default)
			)
			(layer "B.Fab")
		)
		(fp_line
			(start -0.299974 0.150114)
			(end 0.299974 0.150114)
			(stroke
				(width 0.1)
				(type default)
			)
			(layer "B.Fab")
		)
		(fp_line
			(start 0.299974 -0.150114)
			(end -0.299974 -0.150114)
			(stroke
				(width 0.1)
				(type default)
			)
			(layer "B.Fab")
		)
		(fp_line
			(start 0.299974 0.150114)
			(end 0.299974 -0.150114)
			(stroke
				(width 0.1)
				(type default)
			)
			(layer "B.Fab")
		)
		(pad "1" smd rect
			(at 0.2667 0 180)
			(size 0.3048 0.381)
			(layers "B.Cu" "B.Mask" "B.Paste")
			(net "P1V8_AUX")
		)
		(pad "2" smd rect
			(at -0.2667 0 180)
			(size 0.3048 0.381)
			(layers "B.Cu" "B.Mask" "B.Paste")
			(net "GND")
		)
	)
	(footprint ""
		(layer "B.Cu")
		(at 114.086386 -249.368564)
		(property "Reference" "C2338"
			(at 0 0 0)
			(layer "B.SilkS")
			(hide yes)
			(effects
				(font
					(size 1.27 1.27)
				)
				(justify mirror)
			)
		)
		(property "Value" ""
			(at 0 0 0)
			(layer "B.Fab")
			(effects
				(font
					(size 1.27 1.27)
				)
				(justify mirror)
			)
		)
		(duplicate_pad_numbers_are_jumpers no)
		(fp_line
			(start -0.7874 -0.4064)
			(end -0.7874 0.4064)
			(stroke
				(width 0.1524)
				(type default)
			)
			(layer "B.SilkS")
		)
		(fp_line
			(start -0.7874 0.4064)
			(end 0.7874 0.4064)
			(stroke
				(width 0.1524)
				(type default)
			)
			(layer "B.SilkS")
		)
		(fp_line
			(start 0.7874 -0.4064)
			(end -0.7874 -0.4064)
			(stroke
				(width 0.1524)
				(type default)
			)
			(layer "B.SilkS")
		)
		(fp_line
			(start 0.7874 0.4064)
			(end 0.7874 -0.4064)
			(stroke
				(width 0.1524)
				(type default)
			)
			(layer "B.SilkS")
		)
		(fp_line
			(start -0.67945 -0.3048)
			(end -0.67945 0.3048)
			(stroke
				(width 0.1)
				(type default)
			)
			(layer "B.Fab")
		)
		(fp_line
			(start -0.67945 0.3048)
			(end -0.120396 0.3048)
			(stroke
				(width 0.1)
				(type default)
			)
			(layer "B.Fab")
		)
		(fp_line
			(start -0.12065 -0.3048)
			(end -0.67945 -0.3048)
			(stroke
				(width 0.1)
				(type default)
			)
			(layer "B.Fab")
		)
		(fp_line
			(start -0.12065 -0.2794)
			(end -0.12065 -0.3048)
			(stroke
				(width 0.1)
				(type default)
			)
			(layer "B.Fab")
		)
		(fp_line
			(start -0.120396 0.2794)
			(end 0.12065 0.2794)
			(stroke
				(width 0.1)
				(type default)
			)
			(layer "B.Fab")
		)
		(fp_line
			(start -0.120396 0.3048)
			(end -0.120396 0.2794)
			(stroke
				(width 0.1)
				(type default)
			)
			(layer "B.Fab")
		)
		(fp_line
			(start 0.12065 -0.305054)
			(end 0.12065 -0.2794)
			(stroke
				(width 0.1)
				(type default)
			)
			(layer "B.Fab")
		)
		(fp_line
			(start 0.12065 -0.2794)
			(end -0.12065 -0.2794)
			(stroke
				(width 0.1)
				(type default)
			)
			(layer "B.Fab")
		)
		(fp_line
			(start 0.12065 0.2794)
			(end 0.12065 0.3048)
			(stroke
				(width 0.1)
				(type default)
			)
			(layer "B.Fab")
		)
		(fp_line
			(start 0.12065 0.3048)
			(end 0.67945 0.3048)
			(stroke
				(width 0.1)
				(type default)
			)
			(layer "B.Fab")
		)
		(fp_line
			(start 0.67945 -0.305054)
			(end 0.12065 -0.305054)
			(stroke
				(width 0.1)
				(type default)
			)
			(layer "B.Fab")
		)
		(fp_line
			(start 0.67945 0.3048)
			(end 0.67945 -0.305054)
			(stroke
				(width 0.1)
				(type default)
			)
			(layer "B.Fab")
		)
		(pad "1" smd circle
			(at 0.40005 0 180)
			(size 0 0)
			(layers "B.Cu" "B.Mask" "B.Paste")
			(net "PVDDCR_CPU0_P1")
		)
		(pad "2" smd circle
			(at -0.40005 0 180)
			(size 0 0)
			(layers "B.Cu" "B.Mask" "B.Paste")
			(net "GND")
		)
	)
	(footprint ""
		(layer "B.Cu")
		(at 23.577804 -338.08797 -90)
		(property "Reference" "PR378"
			(at 0 0 90)
			(layer "B.SilkS")
			(hide yes)
			(effects
				(font
					(size 1.27 1.27)
				)
				(justify mirror)
			)
		)
		(property "Value" ""
			(at 0 0 90)
			(layer "B.Fab")
			(effects
				(font
					(size 1.27 1.27)
				)
				(justify mirror)
			)
		)
		(duplicate_pad_numbers_are_jumpers no)
		(fp_line
			(start -0.7874 0.4064)
			(end 0.7874 0.4064)
			(stroke
				(width 0.1524)
				(type default)
			)
			(layer "B.SilkS")
		)
		(fp_line
			(start 0.7874 0.4064)
			(end 0.7874 -0.4064)
			(stroke
				(width 0.1524)
				(type default)
			)
			(layer "B.SilkS")
		)
		(fp_line
			(start -0.7874 -0.4064)
			(end -0.7874 0.4064)
			(stroke
				(width 0.1524)
				(type default)
			)
			(layer "B.SilkS")
		)
		(fp_line
			(start 0.7874 -0.4064)
			(end -0.7874 -0.4064)
			(stroke
				(width 0.1524)
				(type default)
			)
			(layer "B.SilkS")
		)
		(fp_line
			(start -0.67945 0.3048)
			(end -0.120396 0.3048)
			(stroke
				(width 0.1)
				(type default)
			)
			(layer "B.Fab")
		)
		(fp_line
			(start -0.120396 0.3048)
			(end -0.120396 0.2794)
			(stroke
				(width 0.1)
				(type default)
			)
			(layer "B.Fab")
		)
		(fp_line
			(start 0.12065 0.3048)
			(end 0.67945 0.3048)
			(stroke
				(width 0.1)
				(type default)
			)
			(layer "B.Fab")
		)
		(fp_line
			(start 0.67945 0.3048)
			(end 0.67945 -0.305054)
			(stroke
				(width 0.1)
				(type default)
			)
			(layer "B.Fab")
		)
		(fp_line
			(start -0.120396 0.2794)
			(end 0.12065 0.2794)
			(stroke
				(width 0.1)
				(type default)
			)
			(layer "B.Fab")
		)
		(fp_line
			(start 0.12065 0.2794)
			(end 0.12065 0.3048)
			(stroke
				(width 0.1)
				(type default)
			)
			(layer "B.Fab")
		)
		(fp_line
			(start -0.12065 -0.2794)
			(end -0.12065 -0.3048)
			(stroke
				(width 0.1)
				(type default)
			)
			(layer "B.Fab")
		)
		(fp_line
			(start 0.12065 -0.2794)
			(end -0.12065 -0.2794)
			(stroke
				(width 0.1)
				(type default)
			)
			(layer "B.Fab")
		)
		(fp_line
			(start -0.67945 -0.3048)
			(end -0.67945 0.3048)
			(stroke
				(width 0.1)
				(type default)
			)
			(layer "B.Fab")
		)
		(fp_line
			(start -0.12065 -0.3048)
			(end -0.67945 -0.3048)
			(stroke
				(width 0.1)
				(type default)
			)
			(layer "B.Fab")
		)
		(fp_line
			(start 0.12065 -0.305054)
			(end 0.12065 -0.2794)
			(stroke
				(width 0.1)
				(type default)
			)
			(layer "B.Fab")
		)
		(fp_line
			(start 0.67945 -0.305054)
			(end 0.12065 -0.305054)
			(stroke
				(width 0.1)
				(type default)
			)
			(layer "B.Fab")
		)
		(pad "1" smd circle
			(at 0.40005 0 90)
			(size 0 0)
			(layers "B.Cu" "B.Mask" "B.Paste")
			(net "PVDDIO_P1")
		)
		(pad "2" smd circle
			(at -0.40005 0 90)
			(size 0 0)
			(layers "B.Cu" "B.Mask" "B.Paste")
			(net "GND")
		)
	)
)
